(kicad_pcb
	(version 20221018)
	(generator pcbnew)
	(general
    (thickness 0.908)
  )
	(paper "A4")
	(title_block
    (title "HDMI-MIPI Bridge")
    (date "2024-04-24")
    (rev "1.3.2")
		(comment 9 "footprints 91-96 of 121")
	)
	(layers
    (0 "F.Cu" signal)
    (1 "In1.Cu" signal)
    (2 "In2.Cu" signal)
    (31 "B.Cu" signal)
    (32 "B.Adhes" user "B.Adhesive")
    (33 "F.Adhes" user "F.Adhesive")
    (34 "B.Paste" user)
    (35 "F.Paste" user)
    (36 "B.SilkS" user "B.Silkscreen")
    (37 "F.SilkS" user "F.Silkscreen")
    (38 "B.Mask" user)
    (39 "F.Mask" user)
    (40 "Dwgs.User" user "User.Drawings")
    (41 "Cmts.User" user "User.Comments")
    (42 "Eco1.User" user "User.Eco1")
    (43 "Eco2.User" user "User.Eco2")
    (44 "Edge.Cuts" user)
    (45 "Margin" user)
    (46 "B.CrtYd" user "B.Courtyard")
    (47 "F.CrtYd" user "F.Courtyard")
    (48 "B.Fab" user)
    (49 "F.Fab" user)
  )
	(footprint "antmicro-footprints:HDMI-A_Receptacle_Molex_471511001" (layer "F.Cu")
    (at 160.999 94.344 180)
    (property "Author" "Antmicro")
    (property "License" "Apache-2.0")
    (property "MPN" "471511001")
    (property "Manufacturer" "Molex")
    (property "Sheetfile" "channel2.kicad_sch")
    (property "Sheetname" "Channel 2")
    (property "ki_description" "HDMI Receptacle Connector 19 Position Surface Mount, Right Angle; Through Hole")
    (property "ki_keywords" "HDMI, CONNECTOR, SMT, HORIZONTAL")
    (attr smd)
    (fp_text reference "J4" (at 9.879 1.614 unlocked) (layer "F.SilkS")
        (effects (font (size 0.7 0.7) (thickness 0.15)) (justify left bottom))
    )
    (fp_text value "HDMI-A_Molex_471511001" (at 0 7.55 180 unlocked) (layer "F.Fab")
        (effects (font (size 0.7 0.7) (thickness 0.15)) (justify left bottom))
    )
    (fp_text user "${REFERENCE}" (at -10.001 12.48 180 unlocked) (layer "F.Fab") hide
        (effects (font (size 0.7 0.7) (thickness 0.15)) (justify left bottom))
    )
    (fp_text user "Author: Antmicro" (at -10.001 13.678 180) (layer "F.Fab") hide
        (effects (font (size 0.7 0.7) (thickness 0.15)) (justify left bottom))
    )
    (fp_text user "License: Apache-2.0" (at -10.001 14.878 180) (layer "F.Fab") hide
        (effects (font (size 0.7 0.7) (thickness 0.15)) (justify left bottom))
    )
    (fp_circle (center 4.948 -5.705) (end 4.998 -5.705)
      (stroke (width 0.15) (type solid)) (fill solid) (layer "F.SilkS"))
    (fp_rect (start -8.0296 -6.5548) (end 8.0296 6.5532)
      (stroke (width 0.05) (type solid)) (fill none) (layer "F.CrtYd"))
    (pad "1" smd rect (at 4.499 -5.056 180) (size 0.3 2.6) (layers "F.Cu" "F.Paste" "F.Mask")
      (net 88 "/Channel 2/HDMI2_D2_P") (pinfunction "D2+") (pintype "bidirectional"))
    (pad "2" smd rect (at 3.999 -5.056 180) (size 0.3 2.6) (layers "F.Cu" "F.Paste" "F.Mask")
      (net 2 "GND") (pinfunction "D2S") (pintype "passive"))
    (pad "3" smd rect (at 3.499 -5.056 180) (size 0.3 2.6) (layers "F.Cu" "F.Paste" "F.Mask")
      (net 89 "/Channel 2/HDMI2_D2_N") (pinfunction "D2-") (pintype "bidirectional"))
    (pad "4" smd rect (at 2.999 -5.056 180) (size 0.3 2.6) (layers "F.Cu" "F.Paste" "F.Mask")
      (net 90 "/Channel 2/HDMI2_D1_P") (pinfunction "D1+") (pintype "bidirectional"))
    (pad "5" smd rect (at 2.499 -5.056 180) (size 0.3 2.6) (layers "F.Cu" "F.Paste" "F.Mask")
      (net 2 "GND") (pinfunction "D1S") (pintype "passive"))
    (pad "6" smd rect (at 1.999 -5.056 180) (size 0.3 2.6) (layers "F.Cu" "F.Paste" "F.Mask")
      (net 91 "/Channel 2/HDMI2_D1_N") (pinfunction "D1-") (pintype "bidirectional"))
    (pad "7" smd rect (at 1.499 -5.056 180) (size 0.3 2.6) (layers "F.Cu" "F.Paste" "F.Mask")
      (net 92 "/Channel 2/HDMI2_D0_P") (pinfunction "D0+") (pintype "bidirectional"))
    (pad "8" smd rect (at 0.998 -5.056 180) (size 0.3 2.6) (layers "F.Cu" "F.Paste" "F.Mask")
      (net 2 "GND") (pinfunction "D0S") (pintype "passive"))
    (pad "9" smd rect (at 0.498 -5.056 180) (size 0.3 2.6) (layers "F.Cu" "F.Paste" "F.Mask")
      (net 93 "/Channel 2/HDMI2_D0_N") (pinfunction "D0-") (pintype "bidirectional"))
    (pad "10" smd rect (at 0 -5.056 180) (size 0.3 2.6) (layers "F.Cu" "F.Paste" "F.Mask")
      (net 94 "/Channel 2/HDMI2_CLK_P") (pinfunction "CK+") (pintype "bidirectional"))
    (pad "11" smd rect (at -0.5 -5.056 180) (size 0.3 2.6) (layers "F.Cu" "F.Paste" "F.Mask")
      (net 2 "GND") (pinfunction "CKS") (pintype "passive"))
    (pad "12" smd rect (at -1.002 -5.056 180) (size 0.3 2.6) (layers "F.Cu" "F.Paste" "F.Mask")
      (net 137 "/Channel 2/HDMI2_CLK_N") (pinfunction "CK-") (pintype "bidirectional"))
    (pad "13" smd rect (at -1.5 -5.056 180) (size 0.3 2.6) (layers "F.Cu" "F.Paste" "F.Mask")
      (net 138 "/Channel 2/HDMI2_CEC") (pinfunction "CEC") (pintype "bidirectional"))
    (pad "14" smd rect (at -2.001 -5.056 180) (size 0.3 2.6) (layers "F.Cu" "F.Paste" "F.Mask")
      (net 95 "/Channel 2/DUMMY2") (pinfunction "UTILITY/HEAC+") (pintype "bidirectional"))
    (pad "15" smd rect (at -2.501 -5.056 180) (size 0.3 2.6) (layers "F.Cu" "F.Paste" "F.Mask")
      (net 139 "/Channel 2/HDMI2_DDC_SCL") (pinfunction "SCL") (pintype "bidirectional"))
    (pad "16" smd rect (at -3 -5.056 180) (size 0.3 2.6) (layers "F.Cu" "F.Paste" "F.Mask")
      (net 140 "/Channel 2/HDMI2_DDC_SDA") (pinfunction "SDA") (pintype "bidirectional"))
    (pad "17" smd rect (at -3.501 -5.056 180) (size 0.3 2.6) (layers "F.Cu" "F.Paste" "F.Mask")
      (net 2 "GND") (pinfunction "GND") (pintype "power_in"))
    (pad "18" smd rect (at -4 -5.056 180) (size 0.3 2.6) (layers "F.Cu" "F.Paste" "F.Mask")
      (net 96 "/Channel 2/HDMI2_POWER") (pinfunction "+5V") (pintype "power_in"))
    (pad "19" smd rect (at -4.502 -5.056 180) (size 0.3 2.6) (layers "F.Cu" "F.Paste" "F.Mask")
      (net 141 "/Channel 2/HDMI2_HPD") (pinfunction "HPD/HEAC-") (pintype "bidirectional"))
    (pad "SH" thru_hole oval (at -7.25 -4.297 180) (size 1.5 3.3) (drill oval 0.9 2.7) (layers "*.Cu" "*.Mask")
      (net 29 "Net-(FB7-Pad2)") (pinfunction "SH") (pintype "passive"))
    (pad "SH" thru_hole oval (at -7.25 1.664 180) (size 1.5 2.3) (drill oval 0.9 1.7) (layers "*.Cu" "*.Mask")
      (net 29 "Net-(FB7-Pad2)") (pinfunction "SH") (pintype "passive"))
    (pad "SH" thru_hole oval (at 7.249 -4.297 180) (size 1.5 3.3) (drill oval 0.9 2.7) (layers "*.Cu" "*.Mask")
      (net 29 "Net-(FB7-Pad2)") (pinfunction "SH") (pintype "passive"))
    (pad "SH" thru_hole oval (at 7.249 1.664 180) (size 1.5 2.3) (drill oval 0.9 1.7) (layers "*.Cu" "*.Mask")
      (net 29 "Net-(FB7-Pad2)") (pinfunction "SH") (pintype "passive"))
  )
	(footprint "antmicro-footprints:C_0603_1608Metric" (layer "F.Cu")
    (at 164.2 113.05 180)
    (descr "Capacitor SMD 0603")
    (tags "capacitor 0603")
    (property "Author" "Antmicro")
    (property "Dielectric" "")
    (property "License" "Apache-2.0")
    (property "MPN" "C1608X5R1V475M080AC")
    (property "Manufacturer" "TDK")
    (property "Public" "False")
    (property "Sheetfile" "channel2.kicad_sch")
    (property "Sheetname" "Channel 2")
    (property "Val" "4u7")
    (property "Voltage" "")
    (property "ki_description" "SMD Multilayer Ceramic Capacitor, 4.7 µF, 35 V, 0603 [1608 Metric], ± 20%, X5R, C")
    (property "ki_keywords" "0603, SMT, CAPACITOR, PASSIVE, CERAMIC, MLCC")
    (attr smd)
    (fp_text reference "C53" (at 2 -6.85) (layer "F.SilkS")
        (effects (font (size 0.65 0.65) (thickness 0.13)) (justify right bottom))
    )
    (fp_text value "C_4u7_0603" (at 0 1.6) (layer "F.Fab")
        (effects (font (size 0.65 0.65) (thickness 0.13)) (justify right bottom))
    )
    (fp_text user "License: Apache-2.0" (at -1.682 5.895) (layer "F.Fab") hide
        (effects (font (size 0.7 0.7) (thickness 0.15)) (justify right bottom))
    )
    (fp_text user "Author: Antmicro" (at -1.682 4.894) (layer "F.Fab") hide
        (effects (font (size 0.7 0.7) (thickness 0.15)) (justify right bottom))
    )
    (fp_text user "${REFERENCE}" (at -1.682 3.895) (layer "F.Fab") hide
        (effects (font (size 0.7 0.7) (thickness 0.15)) (justify right bottom))
    )
    (fp_line (start -0.15 -0.4) (end 0.15 -0.4)
      (stroke (width 0.15) (type solid)) (layer "F.SilkS"))
    (fp_line (start -0.15 0.4) (end 0.15 0.4)
      (stroke (width 0.15) (type solid)) (layer "F.SilkS"))
    (fp_rect (start -1.25 -0.65) (end 1.25 0.65)
      (stroke (width 0.05) (type solid)) (fill none) (layer "F.CrtYd"))
    (fp_rect (start -0.8 -0.4) (end 0.8 0.4)
      (stroke (width 0.15) (type solid)) (fill none) (layer "F.Fab"))
    (pad "1" smd roundrect (at -0.7 0 180) (size 0.8 1) (layers "F.Cu" "F.Paste" "F.Mask") (roundrect_rratio 0.2)
      (net 2 "GND") (pintype "passive"))
    (pad "2" smd roundrect (at 0.7 0 180) (size 0.8 1) (layers "F.Cu" "F.Paste" "F.Mask") (roundrect_rratio 0.2)
      (net 110 "Net-(C49-Pad1)") (pintype "passive"))
  )
	(footprint "antmicro-footprints:R-PDSO-N15" (layer "F.Cu")
    (at 159.25 103.42 90)
    (property "Author" "Antmicro")
    (property "License" "Apache-2.0")
    (property "MPN" "TPD8S009DSMR")
    (property "Manufacturer" "Texas Instruments")
    (property "Sheetfile" "channel2.kicad_sch")
    (property "Sheetname" "Channel 2")
    (property "ki_description" "TVS diode array, 8 kV, R-PDSO-N15, 5.5 V, 0.8 pF")
    (property "ki_keywords" "SMT, DIODE, SEMICONDUCTOR, TVS, ESD")
    (attr smd)
    (fp_text reference "U5" (at 0 -3.7 90) (layer "F.SilkS")
        (effects (font (size 0.65 0.65) (thickness 0.13)) (justify left bottom))
    )
    (fp_text value "TPD8S009DSMR" (at 0 4.4 90) (layer "F.Fab")
        (effects (font (size 0.65 0.65) (thickness 0.13)) (justify left bottom))
    )
    (fp_text user "Author: Antmicro" (at -4.1 7.35 90) (layer "F.Fab") hide
        (effects (font (size 0.7 0.7) (thickness 0.15)) (justify left bottom))
    )
    (fp_text user "License: Apache-2.0" (at -4.1 6.15 90) (layer "F.Fab") hide
        (effects (font (size 0.7 0.7) (thickness 0.15)) (justify left bottom))
    )
    (fp_text user "${REFERENCE}" (at -4.1 4.95 90) (layer "F.Fab") hide
        (effects (font (size 0.7 0.7) (thickness 0.15)) (justify left bottom))
    )
    (fp_circle (center -1.6 -3.2) (end -1.6 -3.15)
      (stroke (width 0.15) (type solid)) (fill solid) (layer "F.SilkS"))
    (fp_rect (start 1.8 -3.5) (end -1.89 3.49)
      (stroke (width 0.05) (type solid)) (fill none) (layer "F.CrtYd"))
    (fp_line (start -1.3 -3.051) (end -1.1 -3.25)
      (stroke (width 0.15) (type solid)) (layer "F.Fab"))
    (fp_rect (start 1.301 -3.25) (end -1.3 3.249)
      (stroke (width 0.15) (type solid)) (fill none) (layer "F.Fab"))
    (pad "1" smd roundrect (at -0.95 -2.75) (size 0.3 1.45) (layers "F.Cu" "F.Paste" "F.Mask") (roundrect_rratio 0.25)
      (net 88 "/Channel 2/HDMI2_D2_P") (pinfunction "D0+") (pintype "passive"))
    (pad "2" smd roundrect (at -0.95 -2.25) (size 0.3 1.45) (layers "F.Cu" "F.Paste" "F.Mask") (roundrect_rratio 0.25)
      (net 2 "GND") (pinfunction "GND") (pintype "passive"))
    (pad "3" smd roundrect (at -0.95 -1.75) (size 0.3 1.45) (layers "F.Cu" "F.Paste" "F.Mask") (roundrect_rratio 0.25)
      (net 89 "/Channel 2/HDMI2_D2_N") (pinfunction "D0-") (pintype "passive"))
    (pad "4" smd roundrect (at -0.95 -1.25) (size 0.3 1.45) (layers "F.Cu" "F.Paste" "F.Mask") (roundrect_rratio 0.25)
      (net 90 "/Channel 2/HDMI2_D1_P") (pinfunction "D1+") (pintype "passive"))
    (pad "5" smd roundrect (at -0.95 -0.75) (size 0.3 1.45) (layers "F.Cu" "F.Paste" "F.Mask") (roundrect_rratio 0.25)
      (net 2 "GND") (pinfunction "GND") (pintype "passive"))
    (pad "6" smd roundrect (at -0.95 -0.25) (size 0.3 1.45) (layers "F.Cu" "F.Paste" "F.Mask") (roundrect_rratio 0.25)
      (net 91 "/Channel 2/HDMI2_D1_N") (pinfunction "D1-") (pintype "passive"))
    (pad "7" smd roundrect (at -0.95 0.247) (size 0.3 1.45) (layers "F.Cu" "F.Paste" "F.Mask") (roundrect_rratio 0.25)
      (net 92 "/Channel 2/HDMI2_D0_P") (pinfunction "D2+") (pintype "passive"))
    (pad "8" smd roundrect (at -0.95 0.747) (size 0.3 1.45) (layers "F.Cu" "F.Paste" "F.Mask") (roundrect_rratio 0.25)
      (net 2 "GND") (pinfunction "GND") (pintype "passive"))
    (pad "9" smd roundrect (at -0.95 1.249) (size 0.3 1.45) (layers "F.Cu" "F.Paste" "F.Mask") (roundrect_rratio 0.25)
      (net 93 "/Channel 2/HDMI2_D0_N") (pinfunction "D2-") (pintype "passive"))
    (pad "10" smd roundrect (at -0.95 1.749) (size 0.3 1.45) (layers "F.Cu" "F.Paste" "F.Mask") (roundrect_rratio 0.25)
      (net 94 "/Channel 2/HDMI2_CLK_P") (pinfunction "D3+") (pintype "passive"))
    (pad "11" smd roundrect (at -0.95 2.249) (size 0.3 1.45) (layers "F.Cu" "F.Paste" "F.Mask") (roundrect_rratio 0.25)
      (net 2 "GND") (pinfunction "GND") (pintype "passive"))
    (pad "12" smd roundrect (at -0.95 2.749) (size 0.3 1.45) (layers "F.Cu" "F.Paste" "F.Mask") (roundrect_rratio 0.25)
      (net 137 "/Channel 2/HDMI2_CLK_N") (pinfunction "D3-") (pintype "passive"))
    (pad "13" smd roundrect (at 0.901 1.499) (size 0.3 1.45) (layers "F.Cu" "F.Paste" "F.Mask") (roundrect_rratio 0.25)
      (net 9 "+3V3") (pinfunction "VCC") (pintype "power_in"))
    (pad "14" smd roundrect (at 0.901 0) (size 0.3 1.45) (layers "F.Cu" "F.Paste" "F.Mask") (roundrect_rratio 0.25)
      (net 143 "unconnected-(U5-NC-Pad14)") (pinfunction "NC") (pintype "no_connect"))
    (pad "15" smd roundrect (at 0.901 -1.5) (size 0.3 1.45) (layers "F.Cu" "F.Paste" "F.Mask") (roundrect_rratio 0.25)
      (net 9 "+3V3") (pinfunction "VCC") (pintype "passive"))
  )
	(footprint "antmicro-footprints:R_0603_1608Metric" (layer "F.Cu")
    (at 139.8 116.1 -90)
    (descr "Resistor SMD 0603")
    (tags "resistor SMD 0603")
    (property "Author" "Antmicro")
    (property "Current" "1A")
    (property "License" "Apache-2.0")
    (property "MPN" "CR0603-J/-000ELF")
    (property "Manufacturer" "Bourns")
    (property "Public" "False")
    (property "Sheetfile" "channel1.kicad_sch")
    (property "Sheetname" "Channel 1")
    (property "Tolerance" "")
    (property "Val" "0R")
    (property "ki_description" "Zero Ohm Resistor, Jumper, 0603 [1608 Metric], Thick Film, 100 mW, 1 A, Surface Mount Device, CR")
    (property "ki_keywords" "0603, SMT, RESISTOR, PASSIVE")
    (attr smd)
    (fp_text reference "R5" (at 2.65 -0.2 -90) (layer "F.SilkS")
        (effects (font (size 0.7 0.7) (thickness 0.15)) (justify left bottom))
    )
    (fp_text value "R_0R_0603" (at 0 1.6 -90) (layer "F.Fab")
        (effects (font (size 0.7 0.7) (thickness 0.15)) (justify left bottom))
    )
    (fp_text user "${REFERENCE}" (at -1.25 3.898 -90) (layer "F.Fab") hide
        (effects (font (size 0.7 0.7) (thickness 0.15)) (justify left bottom))
    )
    (fp_text user "License: Apache-2.0" (at -1.25 5.9 -90) (layer "F.Fab") hide
        (effects (font (size 0.7 0.7) (thickness 0.15)) (justify left bottom))
    )
    (fp_text user "Author: Antmicro" (at -1.25 4.9 -90) (layer "F.Fab") hide
        (effects (font (size 0.7 0.7) (thickness 0.15)) (justify left bottom))
    )
    (fp_line (start -0.15 -0.4) (end 0.15 -0.4)
      (stroke (width 0.15) (type solid)) (layer "F.SilkS"))
    (fp_line (start -0.15 0.4) (end 0.15 0.4)
      (stroke (width 0.15) (type solid)) (layer "F.SilkS"))
    (fp_rect (start -1.25 -0.65) (end 1.25 0.65)
      (stroke (width 0.05) (type solid)) (fill none) (layer "F.CrtYd"))
    (fp_rect (start -0.8 -0.4) (end 0.8 0.4)
      (stroke (width 0.15) (type solid)) (fill none) (layer "F.Fab"))
    (pad "1" smd roundrect (at -0.7 0 270) (size 0.8 1) (layers "F.Cu" "F.Paste" "F.Mask") (roundrect_rratio 0.2)
      (net 19 "Net-(C27-Pad2)") (pintype "passive"))
    (pad "2" smd roundrect (at 0.7 0 270) (size 0.8 1) (layers "F.Cu" "F.Paste" "F.Mask") (roundrect_rratio 0.2)
      (net 8 "Net-(U1B-VDDC1)") (pintype "passive"))
  )
	(footprint "antmicro-footprints:R_0402_1005Metric" (layer "F.Cu")
    (at 167.92 104.81)
    (descr "Resistor SMD 0402")
    (tags "resistor SMD 0402")
    (property "Author" "Antmicro")
    (property "License" "Apache-2.0")
    (property "MPN" "CR0402-FX-1002GLF")
    (property "Manufacturer" "Bourns")
    (property "Public" "False")
    (property "Sheetfile" "channel2.kicad_sch")
    (property "Sheetname" "Channel 2")
    (property "Tolerance" "1%")
    (property "Val" "10k")
    (property "ki_description" "SMD Chip Resistor, 10 kohm, ± 1%, 62.5 mW, 0402 [1005 Metric], Thick Film, General Purpose")
    (property "ki_keywords" "0402, SMT, RESISTOR, PASSIVE")
    (attr smd)
    (fp_text reference "R25" (at 0.905 0.36) (layer "F.SilkS")
        (effects (font (size 0.65 0.65) (thickness 0.13)) (justify left bottom))
    )
    (fp_text value "R_10k_0402" (at 0 1.4) (layer "F.Fab")
        (effects (font (size 0.65 0.65) (thickness 0.13)) (justify left bottom))
    )
    (fp_text user "License: Apache-2.0" (at -0.95 5.169) (layer "F.Fab") hide
        (effects (font (size 0.7 0.7) (thickness 0.15)) (justify left bottom))
    )
    (fp_text user "Author: Antmicro" (at -0.95 4.169) (layer "F.Fab") hide
        (effects (font (size 0.7 0.7) (thickness 0.15)) (justify left bottom))
    )
    (fp_text user "${REFERENCE}" (at -0.95 3.168) (layer "F.Fab") hide
        (effects (font (size 0.7 0.7) (thickness 0.15)) (justify left bottom))
    )
    (fp_rect (start -0.925 -0.47) (end 0.925 0.47)
      (stroke (width 0.05) (type default)) (fill none) (layer "F.CrtYd"))
    (fp_rect (start -0.5 -0.25) (end 0.5 0.25)
      (stroke (width 0.15) (type solid)) (fill none) (layer "F.Fab"))
    (pad "1" smd roundrect (at -0.48 0) (size 0.59 0.64) (layers "F.Cu" "F.Paste" "F.Mask") (roundrect_rratio 0.25)
      (net 140 "/Channel 2/HDMI2_DDC_SDA") (pintype "passive"))
    (pad "2" smd roundrect (at 0.48 0) (size 0.59 0.64) (layers "F.Cu" "F.Paste" "F.Mask") (roundrect_rratio 0.25)
      (net 14 "+5V") (pintype "passive"))
  )
	(footprint "antmicro-footprints:TP_SMD_0.75mm" (layer "B.Cu")
    (at 131.4 115 180)
    (property "Author" "Antmicro")
    (property "License" "Apache-2.0")
    (property "MPN" "")
    (property "Manufacturer" "")
    (property "Public" "False")
    (property "Sheetfile" "channel1.kicad_sch")
    (property "Sheetname" "Channel 1")
    (property "exclude_from_bom" "")
    (property "ki_description" "SMT test point")
    (property "ki_keywords" "TESTPOINT")
    (attr exclude_from_pos_files exclude_from_bom)
    (fp_text reference "TP2" (at -2.66 -0.45) (layer "B.SilkS")
        (effects (font (size 0.65 0.65) (thickness 0.13)) (justify left bottom mirror))
    )
    (fp_text value "TP_0.75mm_SMD" (at 0 -1.2) (layer "B.Fab")
        (effects (font (size 0.65 0.65) (thickness 0.13)) (justify left bottom mirror))
    )
    (fp_text user "License: Apache-2.0" (at -0.4 -5.101) (layer "B.Fab") hide
        (effects (font (size 0.7 0.7) (thickness 0.15)) (justify left bottom mirror))
    )
    (fp_text user "${REFERENCE}" (at -0.4 -2.7) (layer "B.Fab") hide
        (effects (font (size 0.7 0.7) (thickness 0.15)) (justify left bottom mirror))
    )
    (fp_text user "Author: Antmicro" (at -0.4 -3.901) (layer "B.Fab") hide
        (effects (font (size 0.7 0.7) (thickness 0.15)) (justify left bottom mirror))
    )
    (pad "1" smd circle (at 0 0 180) (size 0.75 0.75) (layers "B.Cu" "B.Mask")
      (net 117 "Net-(U1A-EDID_SCL)") (pinfunction "1") (pintype "passive"))
  )
)
